# HDD Back Plane_Stackup.xlsx — Stackup_Design_Flow (pcb-stackup)
| Step1 : |
| SI Team試算疊構，提供厚度、DK、DF、線寬、線距、選用材料(middle loss, low loss…)、選用銅箔粗糙度(HTE, VLP, RTF…)、阻抗計算結果，損耗試算結果等資訊給各家PCB板廠。 |
| Step2 : |
| 各家PCB板廠試算後回傳微調後的疊構資訊(厚度、DK、DF、線寬、線距、阻抗、GLASS TYPE、COPPER TYPE、85ohm loss dB/inch @4GHz and 8GHz)， |
| 並提供試算阻抗與損耗的軟體截圖，有疊構上的疑問會在這個階段討論。 |
| Step3 : |
| SI Team檢視各家PCB板廠的疊構，並決定是否要調整最後給EE與layout的疊構。 |
| Step4 : |
| 採購提供最後的疊構給各家PCB板廠進行備料。 |
| Step5 : |
| Layout根據疊構中的線寬與線距進行佈線。 |
| Step6 : |
| Layout釋出gerber file與疊構給各家PCB板廠，如果後來有修改會透過PDM系統通知板廠。 |
| Step7 : |
| 各家PCB板廠寄出工程問題(EQ)確認的信件，等待SI, EE, Layout的回覆。 |
